# S9S_MB_2U (Grand Teton) — schematic netlist excerpt (pin names and nets, part order shuffled) for the footprints in the layout excerpt that follows; sources: Cadence DE-HDL packaged netlist, KiCad conversion of 03242023_DA0F0TMBIJ0_F0T_Motherboard_J_brd_V01_OCP.brd

R752  Q_RES  10 1% CHIP  pkg 0402LF  page 132 : A = JTAG_DBP_TDO ; B = JTAG_DBP_TDO_PCH
C430  Q_CAP  22UF 4V 20% X6S  pkg C0402  page 77 : A = PVCCFA_EHV_FIVRA_CPU1 ; B = GND

(kicad_pcb
	(version 20260206)
	(generator "pcbnew")
	(generator_version "10.0")
	(general
		(thickness 1.6)
		(legacy_teardrops no)
	)
	(paper "A4")
	(title_block
		(title "03242023_DA0F0TMBIJ0_F0T_Motherboard_J_brd_V01_OCP.brd")
		(comment 1 "Grand Teton / footprints 126-127 of 6105")
	)
	(layers
		(0 "F.Cu" signal "TOP")
		(4 "In1.Cu" signal "GND")
		(6 "In2.Cu" signal "IN1")
		(8 "In3.Cu" signal "GND1")
		(10 "In4.Cu" signal "IN2")
		(12 "In5.Cu" signal "GND2")
		(14 "In6.Cu" signal "IN3")
		(16 "In7.Cu" signal "GND3")
		(18 "In8.Cu" signal "VCC")
		(20 "In9.Cu" signal "VCC1")
		(22 "In10.Cu" signal "GND4")
		(24 "In11.Cu" signal "IN4")
		(26 "In12.Cu" signal "GND5")
		(28 "In13.Cu" signal "IN5")
		(30 "In14.Cu" signal "GND6")
		(32 "In15.Cu" signal "IN6")
		(34 "In16.Cu" signal "GND7")
		(2 "B.Cu" signal "BOTTOM")
		(9 "F.Adhes" user "F.Adhesive")
		(11 "B.Adhes" user "B.Adhesive")
		(13 "F.Paste" user "Package Geometry/Pastemask Top")
		(15 "B.Paste" user "Package Geometry/Pastemask Bottom")
		(5 "F.SilkS" user "Ref Des/Silkscreen Top")
		(7 "B.SilkS" user "Ref Des/Silkscreen Bottom")
		(1 "F.Mask" user "Board Geometry/Soldermask Top")
		(3 "B.Mask" user "Board Geometry/Soldermask Bottom")
		(17 "Dwgs.User" user "User.Drawings")
		(19 "Cmts.User" user "User.Comments")
		(21 "Eco1.User" user "User.Eco1")
		(23 "Eco2.User" user "User.Eco2")
		(25 "Edge.Cuts" user "Board Geometry/Outline")
		(27 "Margin" user)
		(31 "F.CrtYd" user "Package Geometry/Place Bound Top")
		(29 "B.CrtYd" user "Package Geometry/Place Bound Bottom")
		(35 "F.Fab" user "Ref Des/Assembly Top")
		(33 "B.Fab" user "Ref Des/Assembly Bottom")
	)
	(footprint ""
		(layer "F.Cu")
		(at 104.34193 -240.277142 90)
		(property "Reference" "C430"
			(at 0 0 90)
			(layer "F.SilkS")
			(hide yes)
			(effects
				(font
					(size 1.27 1.27)
				)
			)
		)
		(property "Value" ""
			(at 0 0 90)
			(layer "F.Fab")
			(effects
				(font
					(size 1.27 1.27)
				)
			)
		)
		(duplicate_pad_numbers_are_jumpers no)
		(fp_line
			(start 0.7874 -0.4064)
			(end 0.7874 0.4064)
			(stroke
				(width 0.1524)
				(type default)
			)
			(layer "F.SilkS")
		)
		(fp_line
			(start -0.7874 -0.4064)
			(end 0.7874 -0.4064)
			(stroke
				(width 0.1524)
				(type default)
			)
			(layer "F.SilkS")
		)
		(fp_line
			(start 0.7874 0.4064)
			(end -0.7874 0.4064)
			(stroke
				(width 0.1524)
				(type default)
			)
			(layer "F.SilkS")
		)
		(fp_line
			(start -0.7874 0.4064)
			(end -0.7874 -0.4064)
			(stroke
				(width 0.1524)
				(type default)
			)
			(layer "F.SilkS")
		)
		(fp_line
			(start -0.12065 -0.305054)
			(end -0.12065 -0.2794)
			(stroke
				(width 0.1)
				(type default)
			)
			(layer "F.Fab")
		)
		(fp_line
			(start -0.67945 -0.305054)
			(end -0.12065 -0.305054)
			(stroke
				(width 0.1)
				(type default)
			)
			(layer "F.Fab")
		)
		(fp_line
			(start 0.67945 -0.3048)
			(end 0.67945 0.3048)
			(stroke
				(width 0.1)
				(type default)
			)
			(layer "F.Fab")
		)
		(fp_line
			(start 0.12065 -0.3048)
			(end 0.67945 -0.3048)
			(stroke
				(width 0.1)
				(type default)
			)
			(layer "F.Fab")
		)
		(fp_line
			(start 0.12065 -0.2794)
			(end 0.12065 -0.3048)
			(stroke
				(width 0.1)
				(type default)
			)
			(layer "F.Fab")
		)
		(fp_line
			(start -0.12065 -0.2794)
			(end 0.12065 -0.2794)
			(stroke
				(width 0.1)
				(type default)
			)
			(layer "F.Fab")
		)
		(fp_line
			(start 0.120396 0.2794)
			(end -0.12065 0.2794)
			(stroke
				(width 0.1)
				(type default)
			)
			(layer "F.Fab")
		)
		(fp_line
			(start -0.12065 0.2794)
			(end -0.12065 0.3048)
			(stroke
				(width 0.1)
				(type default)
			)
			(layer "F.Fab")
		)
		(fp_line
			(start 0.67945 0.3048)
			(end 0.120396 0.3048)
			(stroke
				(width 0.1)
				(type default)
			)
			(layer "F.Fab")
		)
		(fp_line
			(start 0.120396 0.3048)
			(end 0.120396 0.2794)
			(stroke
				(width 0.1)
				(type default)
			)
			(layer "F.Fab")
		)
		(fp_line
			(start -0.12065 0.3048)
			(end -0.67945 0.3048)
			(stroke
				(width 0.1)
				(type default)
			)
			(layer "F.Fab")
		)
		(fp_line
			(start -0.67945 0.3048)
			(end -0.67945 -0.305054)
			(stroke
				(width 0.1)
				(type default)
			)
			(layer "F.Fab")
		)
		(pad "1" smd circle
			(at -0.40005 0 90)
			(size 0 0)
			(layers "F.Cu" "F.Mask" "F.Paste")
			(net "PVCCFA_EHV_FIVRA_CPU1")
		)
		(pad "2" smd circle
			(at 0.40005 0 90)
			(size 0 0)
			(layers "F.Cu" "F.Mask" "F.Paste")
			(net "GND")
		)
	)
	(footprint ""
		(layer "F.Cu")
		(at 374.112282 -59.295792)
		(property "Reference" "R752"
			(at 0 0 0)
			(layer "F.SilkS")
			(hide yes)
			(effects
				(font
					(size 1.27 1.27)
				)
			)
		)
		(property "Value" ""
			(at 0 0 0)
			(layer "F.Fab")
			(effects
				(font
					(size 1.27 1.27)
				)
			)
		)
		(duplicate_pad_numbers_are_jumpers no)
		(fp_line
			(start -0.7874 -0.4064)
			(end 0.7874 -0.4064)
			(stroke
				(width 0.1524)
				(type default)
			)
			(layer "F.SilkS")
		)
		(fp_line
			(start -0.7874 0.4064)
			(end -0.7874 -0.4064)
			(stroke
				(width 0.1524)
				(type default)
			)
			(layer "F.SilkS")
		)
		(fp_line
			(start 0.7874 -0.4064)
			(end 0.7874 0.4064)
			(stroke
				(width 0.1524)
				(type default)
			)
			(layer "F.SilkS")
		)
		(fp_line
			(start 0.7874 0.4064)
			(end -0.7874 0.4064)
			(stroke
				(width 0.1524)
				(type default)
			)
			(layer "F.SilkS")
		)
		(fp_line
			(start -0.67945 -0.305054)
			(end -0.12065 -0.305054)
			(stroke
				(width 0.1)
				(type default)
			)
			(layer "F.Fab")
		)
		(fp_line
			(start -0.67945 0.3048)
			(end -0.67945 -0.305054)
			(stroke
				(width 0.1)
				(type default)
			)
			(layer "F.Fab")
		)
		(fp_line
			(start -0.12065 -0.305054)
			(end -0.12065 -0.2794)
			(stroke
				(width 0.1)
				(type default)
			)
			(layer "F.Fab")
		)
		(fp_line
			(start -0.12065 -0.2794)
			(end 0.12065 -0.2794)
			(stroke
				(width 0.1)
				(type default)
			)
			(layer "F.Fab")
		)
		(fp_line
			(start -0.12065 0.2794)
			(end -0.12065 0.3048)
			(stroke
				(width 0.1)
				(type default)
			)
			(layer "F.Fab")
		)
		(fp_line
			(start -0.12065 0.3048)
			(end -0.67945 0.3048)
			(stroke
				(width 0.1)
				(type default)
			)
			(layer "F.Fab")
		)
		(fp_line
			(start 0.120396 0.2794)
			(end -0.12065 0.2794)
			(stroke
				(width 0.1)
				(type default)
			)
			(layer "F.Fab")
		)
		(fp_line
			(start 0.120396 0.3048)
			(end 0.120396 0.2794)
			(stroke
				(width 0.1)
				(type default)
			)
			(layer "F.Fab")
		)
		(fp_line
			(start 0.12065 -0.3048)
			(end 0.67945 -0.3048)
			(stroke
				(width 0.1)
				(type default)
			)
			(layer "F.Fab")
		)
		(fp_line
			(start 0.12065 -0.2794)
			(end 0.12065 -0.3048)
			(stroke
				(width 0.1)
				(type default)
			)
			(layer "F.Fab")
		)
		(fp_line
			(start 0.67945 -0.3048)
			(end 0.67945 0.3048)
			(stroke
				(width 0.1)
				(type default)
			)
			(layer "F.Fab")
		)
		(fp_line
			(start 0.67945 0.3048)
			(end 0.120396 0.3048)
			(stroke
				(width 0.1)
				(type default)
			)
			(layer "F.Fab")
		)
		(pad "1" smd circle
			(at -0.40005 0)
			(size 0 0)
			(layers "F.Cu" "F.Mask" "F.Paste")
			(net "JTAG_DBP_TDO")
		)
		(pad "2" smd circle
			(at 0.40005 0)
			(size 0 0)
			(layers "F.Cu" "F.Mask" "F.Paste")
			(net "JTAG_DBP_TDO_PCH")
		)
	)
)
